# T6G (Grand Teton) — schematic netlist excerpt (pin names and nets, part order shuffled) for the footprints in the layout excerpt that follows; sources: Cadence DE-HDL packaged netlist, KiCad conversion of 04192023_DAF0TMB3IC0_F0TG_MB_C_brd_V02_OCP.brd

U57  SCHOTTKY_DUAL_12A_3C  BAT54CW EMPTY  pkg SOT323  page 169
  B  = P12V_AUX_DSC_VOL
  A  = NC
  C  = P12V_AUX_DSC_S1

TP17  TP  NA  pkg TP  page 54 : TP = VSENSE_PVDDCR_CPU0_P1_DP
R1745  Q_RES  10K 1% CHIP  pkg 0402LF  page 171 : A = P3V3_AUX ; B = JTAG_SCM_MUX_TDO

(kicad_pcb
	(version 20260206)
	(generator "pcbnew")
	(generator_version "10.0")
	(general
		(thickness 1.6)
		(legacy_teardrops no)
	)
	(paper "A4")
	(title_block
		(title "04192023_DAF0TMB3IC0_F0TG_MB_C_brd_V02_OCP.brd")
		(comment 1 "Grand Teton / footprints 490-492 of 8354")
	)
	(layers
		(0 "F.Cu" signal "TOP")
		(4 "In1.Cu" signal "GND")
		(6 "In2.Cu" signal "IN1")
		(8 "In3.Cu" signal "GND1")
		(10 "In4.Cu" signal "IN2")
		(12 "In5.Cu" signal "GND2")
		(14 "In6.Cu" signal "IN3")
		(16 "In7.Cu" signal "GND3")
		(18 "In8.Cu" signal "VCC")
		(20 "In9.Cu" signal "VCC1")
		(22 "In10.Cu" signal "GND4")
		(24 "In11.Cu" signal "IN4")
		(26 "In12.Cu" signal "GND5")
		(28 "In13.Cu" signal "IN5")
		(30 "In14.Cu" signal "GND6")
		(32 "In15.Cu" signal "IN6")
		(34 "In16.Cu" signal "GND7")
		(2 "B.Cu" signal "BOTTOM")
		(9 "F.Adhes" user "F.Adhesive")
		(11 "B.Adhes" user "B.Adhesive")
		(13 "F.Paste" user "Package Geometry/Pastemask Top")
		(15 "B.Paste" user "Package Geometry/Pastemask Bottom")
		(5 "F.SilkS" user "Ref Des/Silkscreen Top")
		(7 "B.SilkS" user "Ref Des/Silkscreen Bottom")
		(1 "F.Mask" user "Board Geometry/Soldermask Top")
		(3 "B.Mask" user "Board Geometry/Soldermask Bottom")
		(17 "Dwgs.User" user "User.Drawings")
		(19 "Cmts.User" user "User.Comments")
		(21 "Eco1.User" user "User.Eco1")
		(23 "Eco2.User" user "User.Eco2")
		(25 "Edge.Cuts" user "Board Geometry/Outline")
		(27 "Margin" user)
		(31 "F.CrtYd" user "Package Geometry/Place Bound Top")
		(29 "B.CrtYd" user "Package Geometry/Place Bound Bottom")
		(35 "F.Fab" user "Ref Des/Assembly Top")
		(33 "B.Fab" user "Ref Des/Assembly Bottom")
	)
	(footprint ""
		(layer "F.Cu")
		(at 123.871736 -59.182)
		(property "Reference" "R1745"
			(at 0 0 0)
			(layer "F.SilkS")
			(hide yes)
			(effects
				(font
					(size 1.27 1.27)
				)
			)
		)
		(property "Value" ""
			(at 0 0 0)
			(layer "F.Fab")
			(effects
				(font
					(size 1.27 1.27)
				)
			)
		)
		(duplicate_pad_numbers_are_jumpers no)
		(fp_line
			(start -0.7874 -0.4064)
			(end 0.7874 -0.4064)
			(stroke
				(width 0.1524)
				(type default)
			)
			(layer "F.SilkS")
		)
		(fp_line
			(start -0.7874 0.4064)
			(end -0.7874 -0.4064)
			(stroke
				(width 0.1524)
				(type default)
			)
			(layer "F.SilkS")
		)
		(fp_line
			(start 0.7874 -0.4064)
			(end 0.7874 0.4064)
			(stroke
				(width 0.1524)
				(type default)
			)
			(layer "F.SilkS")
		)
		(fp_line
			(start 0.7874 0.4064)
			(end -0.7874 0.4064)
			(stroke
				(width 0.1524)
				(type default)
			)
			(layer "F.SilkS")
		)
		(fp_line
			(start -0.67945 -0.305054)
			(end -0.12065 -0.305054)
			(stroke
				(width 0.1)
				(type default)
			)
			(layer "F.Fab")
		)
		(fp_line
			(start -0.67945 0.3048)
			(end -0.67945 -0.305054)
			(stroke
				(width 0.1)
				(type default)
			)
			(layer "F.Fab")
		)
		(fp_line
			(start -0.12065 -0.305054)
			(end -0.12065 -0.2794)
			(stroke
				(width 0.1)
				(type default)
			)
			(layer "F.Fab")
		)
		(fp_line
			(start -0.12065 -0.2794)
			(end 0.12065 -0.2794)
			(stroke
				(width 0.1)
				(type default)
			)
			(layer "F.Fab")
		)
		(fp_line
			(start -0.12065 0.2794)
			(end -0.12065 0.3048)
			(stroke
				(width 0.1)
				(type default)
			)
			(layer "F.Fab")
		)
		(fp_line
			(start -0.12065 0.3048)
			(end -0.67945 0.3048)
			(stroke
				(width 0.1)
				(type default)
			)
			(layer "F.Fab")
		)
		(fp_line
			(start 0.120396 0.2794)
			(end -0.12065 0.2794)
			(stroke
				(width 0.1)
				(type default)
			)
			(layer "F.Fab")
		)
		(fp_line
			(start 0.120396 0.3048)
			(end 0.120396 0.2794)
			(stroke
				(width 0.1)
				(type default)
			)
			(layer "F.Fab")
		)
		(fp_line
			(start 0.12065 -0.3048)
			(end 0.67945 -0.3048)
			(stroke
				(width 0.1)
				(type default)
			)
			(layer "F.Fab")
		)
		(fp_line
			(start 0.12065 -0.2794)
			(end 0.12065 -0.3048)
			(stroke
				(width 0.1)
				(type default)
			)
			(layer "F.Fab")
		)
		(fp_line
			(start 0.67945 -0.3048)
			(end 0.67945 0.3048)
			(stroke
				(width 0.1)
				(type default)
			)
			(layer "F.Fab")
		)
		(fp_line
			(start 0.67945 0.3048)
			(end 0.120396 0.3048)
			(stroke
				(width 0.1)
				(type default)
			)
			(layer "F.Fab")
		)
		(pad "1" smd circle
			(at -0.40005 0)
			(size 0 0)
			(layers "F.Cu" "F.Mask" "F.Paste")
			(net "P3V3_AUX")
		)
		(pad "2" smd circle
			(at 0.40005 0)
			(size 0 0)
			(layers "F.Cu" "F.Mask" "F.Paste")
			(net "JTAG_SCM_MUX_TDO")
		)
	)
	(footprint ""
		(layer "F.Cu")
		(at 57.697878 -181.84241)
		(property "Reference" "TP17"
			(at -2.071878 1.52908 0)
			(unlocked yes)
			(layer "F.SilkS")
			(effects
				(font
					(size 0.7874 0.5842)
					(thickness 0.1524)
				)
				(justify left)
			)
		)
		(property "Value" ""
			(at 0 0 0)
			(layer "F.Fab")
			(effects
				(font
					(size 1.27 1.27)
				)
			)
		)
		(duplicate_pad_numbers_are_jumpers no)
		(pad "1" smd circle
			(at 0 0)
			(size 0.762 0.762)
			(layers "F.Cu" "F.Mask" "F.Paste")
			(net "VSENSE_PVDDCR_CPU0_P1_DP")
		)
	)
	(footprint ""
		(layer "F.Cu")
		(at 40.6527 -102.5525 90)
		(property "Reference" "U57"
			(at -1.4224 -1.844548 90)
			(unlocked yes)
			(layer "F.SilkS")
			(effects
				(font
					(size 0.7874 0.5842)
					(thickness 0.1524)
				)
				(justify left)
			)
		)
		(property "Value" ""
			(at 0 0 90)
			(layer "F.Fab")
			(effects
				(font
					(size 1.27 1.27)
				)
			)
		)
		(duplicate_pad_numbers_are_jumpers no)
		(fp_line
			(start 1.335278 -1.100074)
			(end -1.335278 -1.100074)
			(stroke
				(width 0.1524)
				(type default)
			)
			(layer "F.SilkS")
		)
		(fp_line
			(start -1.335278 -1.100074)
			(end -1.335278 1.100074)
			(stroke
				(width 0.1524)
				(type default)
			)
			(layer "F.SilkS")
		)
		(fp_line
			(start 1.335278 1.100074)
			(end 1.335278 -1.100074)
			(stroke
				(width 0.1524)
				(type default)
			)
			(layer "F.SilkS")
		)
		(fp_line
			(start -1.335278 1.100074)
			(end 1.335278 1.100074)
			(stroke
				(width 0.1524)
				(type default)
			)
			(layer "F.SilkS")
		)
		(fp_line
			(start 0.674878 -1.100074)
			(end -0.674878 -1.100074)
			(stroke
				(width 0.1)
				(type default)
			)
			(layer "F.Fab")
		)
		(fp_line
			(start -0.674878 -1.100074)
			(end -0.674878 1.100074)
			(stroke
				(width 0.1)
				(type default)
			)
			(layer "F.Fab")
		)
		(fp_line
			(start 0.674878 1.100074)
			(end 0.674878 -1.100074)
			(stroke
				(width 0.1)
				(type default)
			)
			(layer "F.Fab")
		)
		(fp_line
			(start -0.674878 1.100074)
			(end 0.674878 1.100074)
			(stroke
				(width 0.1)
				(type default)
			)
			(layer "F.Fab")
		)
		(pad "1" smd rect
			(at -0.8001 0.649986)
			(size 0.6096 0.8128)
			(layers "F.Cu" "F.Mask" "F.Paste")
			(net "P12V_AUX_DSC_VOL")
		)
		(pad "2" smd rect
			(at -0.8001 -0.649986)
			(size 0.6096 0.8128)
			(layers "F.Cu" "F.Mask" "F.Paste")
			(net "Net_10857")
		)
		(pad "3" smd rect
			(at 0.8001 0)
			(size 0.6096 0.8128)
			(layers "F.Cu" "F.Mask" "F.Paste")
			(net "P12V_AUX_DSC_S1")
		)
	)
)
